(kicad_pcb
	(version 20241229)
	(generator "pcbnew")
	(generator_version "9.0")
	(general
		(thickness 1.294)
		(legacy_teardrops no)
	)
	(paper "A3")
	(title_block
		(title "Kintex 410T devboard")
		(date "2024-04-03")
		(rev "1.1.2")
		(comment 9 "footprints 934-939 of 975")
	)
	(layers
		(0 "F.Cu" mixed)
		(4 "In1.Cu" power)
		(6 "In2.Cu" power)
		(8 "In3.Cu" mixed)
		(10 "In4.Cu" power)
		(12 "In5.Cu" mixed)
		(14 "In6.Cu" power)
		(16 "In7.Cu" mixed)
		(18 "In8.Cu" power)
		(2 "B.Cu" mixed)
		(9 "F.Adhes" user "F.Adhesive")
		(11 "B.Adhes" user "B.Adhesive")
		(13 "F.Paste" user)
		(15 "B.Paste" user)
		(5 "F.SilkS" user "F.Silkscreen")
		(7 "B.SilkS" user "B.Silkscreen")
		(1 "F.Mask" user)
		(3 "B.Mask" user)
		(17 "Dwgs.User" user "User.Drawings")
		(19 "Cmts.User" user "User.Comments")
		(21 "Eco1.User" user "User.Eco1")
		(23 "Eco2.User" user "User.Eco2")
		(25 "Edge.Cuts" user)
		(27 "Margin" user)
		(31 "F.CrtYd" user "F.Courtyard")
		(29 "B.CrtYd" user "B.Courtyard")
		(35 "F.Fab" user)
		(33 "B.Fab" user)
	)
	(footprint "antmicro-footprints:C_0402_1005Metric"
		(layer "B.Cu")
		(at 158.6 146.5 -90)
		(descr "Capacitor SMD 0402")
		(tags "capacitor SMD 0402")
		(property "Reference" "C172"
			(at -1.025 3.475 90)
			(layer "B.SilkS")
			(effects
				(font
					(size 0.7 0.7)
					(thickness 0.15)
				)
				(justify left bottom mirror)
			)
		)
		(property "Value" "C_100n_0402"
			(at 0 -1.169 90)
			(layer "B.Fab")
			(effects
				(font
					(size 0.7 0.7)
					(thickness 0.15)
				)
				(justify left bottom mirror)
			)
		)
		(property "Description" "SMD Multilayer Ceramic Capacitor, 0.1 µF, 50 V, 0402 [1005 Metric], ± 10%, X5R, GRM Series"
			(at 0 0 270)
			(layer "F.Fab")
			(hide yes)
			(effects
				(font
					(size 1.27 1.27)
					(thickness 0.15)
				)
			)
		)
		(property "Author" "Antmicro"
			(at 12.1 305.1 0)
			(layer "B.Fab")
			(hide yes)
			(effects
				(font
					(size 1 1)
					(thickness 0.15)
				)
				(justify mirror)
			)
		)
		(property "Dielectric" "X5R"
			(at 12.1 305.1 0)
			(layer "B.Fab")
			(hide yes)
			(effects
				(font
					(size 1 1)
					(thickness 0.15)
				)
				(justify mirror)
			)
		)
		(property "License" "Apache-2.0"
			(at 12.1 305.1 0)
			(layer "B.Fab")
			(hide yes)
			(effects
				(font
					(size 1 1)
					(thickness 0.15)
				)
				(justify mirror)
			)
		)
		(property "MPN" "GRM155R61H104KE14D"
			(at 12.1 305.1 0)
			(layer "B.Fab")
			(hide yes)
			(effects
				(font
					(size 1 1)
					(thickness 0.15)
				)
				(justify mirror)
			)
		)
		(property "Manufacturer" "Murata"
			(at 12.1 305.1 0)
			(layer "B.Fab")
			(hide yes)
			(effects
				(font
					(size 1 1)
					(thickness 0.15)
				)
				(justify mirror)
			)
		)
		(property "Val" "100n"
			(at 12.1 305.1 0)
			(layer "B.Fab")
			(hide yes)
			(effects
				(font
					(size 1 1)
					(thickness 0.15)
				)
				(justify mirror)
			)
		)
		(property "Voltage" "50V"
			(at 12.1 305.1 0)
			(layer "B.Fab")
			(hide yes)
			(effects
				(font
					(size 1 1)
					(thickness 0.15)
				)
				(justify mirror)
			)
		)
		(sheetname "DRAM + SRAM")
		(sheetfile "ram.kicad_sch")
		(attr smd)
		(fp_rect
			(start -0.925 0.47)
			(end 0.925 -0.47)
			(stroke
				(width 0.05)
				(type default)
			)
			(fill no)
			(layer "B.CrtYd")
		)
		(fp_line
			(start -0.494 0.25)
			(end 0.504 0.25)
			(stroke
				(width 0.15)
				(type solid)
			)
			(layer "B.Fab")
		)
		(fp_line
			(start 0.504 0.25)
			(end 0.504 -0.248)
			(stroke
				(width 0.15)
				(type solid)
			)
			(layer "B.Fab")
		)
		(fp_line
			(start -0.494 -0.248)
			(end -0.494 0.25)
			(stroke
				(width 0.15)
				(type solid)
			)
			(layer "B.Fab")
		)
		(fp_line
			(start 0.504 -0.248)
			(end -0.494 -0.248)
			(stroke
				(width 0.15)
				(type solid)
			)
			(layer "B.Fab")
		)
		(pad "1" smd roundrect
			(at -0.48 0 270)
			(size 0.59 0.64)
			(layers "B.Cu" "B.Mask" "B.Paste")
			(roundrect_rratio 0.25)
			(net 7 "+0V675_VTT")
			(pintype "passive")
		)
		(pad "2" smd roundrect
			(at 0.48 0 270)
			(size 0.59 0.64)
			(layers "B.Cu" "B.Mask" "B.Paste")
			(roundrect_rratio 0.25)
			(net 25 "+1V35")
			(pintype "passive")
		)
	)
	(footprint "antmicro-footprints:R_0402_1005Metric"
		(layer "B.Cu")
		(at 201.891252 99.25 90)
		(descr "Resistor SMD 0402")
		(tags "resistor SMD 0402")
		(property "Reference" "R239"
			(at -3.8 0.358748 270)
			(layer "B.SilkS")
			(effects
				(font
					(size 0.7 0.7)
					(thickness 0.15)
				)
				(justify left bottom mirror)
			)
		)
		(property "Value" "R_10k_0402"
			(at 0 -1.4 270)
			(layer "B.Fab")
			(effects
				(font
					(size 0.7 0.7)
					(thickness 0.15)
				)
				(justify left bottom mirror)
			)
		)
		(property "Description" "SMD Chip Resistor, 10 kohm, ± 1%, 62.5 mW, 0402 [1005 Metric], Thick Film, General Purpose"
			(at 0 0 90)
			(layer "F.Fab")
			(hide yes)
			(effects
				(font
					(size 1.27 1.27)
					(thickness 0.15)
				)
			)
		)
		(property "Author" "Antmicro"
			(at 301.141252 -102.641252 0)
			(layer "B.Fab")
			(hide yes)
			(effects
				(font
					(size 1 1)
					(thickness 0.15)
				)
				(justify mirror)
			)
		)
		(property "License" "Apache-2.0"
			(at 301.141252 -102.641252 0)
			(layer "B.Fab")
			(hide yes)
			(effects
				(font
					(size 1 1)
					(thickness 0.15)
				)
				(justify mirror)
			)
		)
		(property "MPN" "CR0402-FX-1002GLF"
			(at 301.141252 -102.641252 0)
			(layer "B.Fab")
			(hide yes)
			(effects
				(font
					(size 1 1)
					(thickness 0.15)
				)
				(justify mirror)
			)
		)
		(property "Manufacturer" "Bourns"
			(at 301.141252 -102.641252 0)
			(layer "B.Fab")
			(hide yes)
			(effects
				(font
					(size 1 1)
					(thickness 0.15)
				)
				(justify mirror)
			)
		)
		(property "Tolerance" "1%"
			(at 301.141252 -102.641252 0)
			(layer "B.Fab")
			(hide yes)
			(effects
				(font
					(size 1 1)
					(thickness 0.15)
				)
				(justify mirror)
			)
		)
		(property "Val" "10k"
			(at 301.141252 -102.641252 0)
			(layer "B.Fab")
			(hide yes)
			(effects
				(font
					(size 1 1)
					(thickness 0.15)
				)
				(justify mirror)
			)
		)
		(sheetname "HDMI + Ethernet")
		(sheetfile "hdmi-ethernet.kicad_sch")
		(attr smd)
		(fp_rect
			(start -0.925 0.47)
			(end 0.925 -0.47)
			(stroke
				(width 0.05)
				(type default)
			)
			(fill no)
			(layer "B.CrtYd")
		)
		(fp_rect
			(start -0.5 0.25)
			(end 0.5 -0.25)
			(stroke
				(width 0.15)
				(type solid)
			)
			(fill no)
			(layer "B.Fab")
		)
		(pad "1" smd roundrect
			(at -0.48 0 90)
			(size 0.59 0.64)
			(layers "B.Cu" "B.Mask" "B.Paste")
			(roundrect_rratio 0.25)
			(net 24 "+3V3")
			(pintype "passive")
		)
		(pad "2" smd roundrect
			(at 0.48 0 90)
			(size 0.59 0.64)
			(layers "B.Cu" "B.Mask" "B.Paste")
			(roundrect_rratio 0.25)
			(net 522 "/FPGA Bank 16 & 17/GBE_RGMII.~{RESET}")
			(pintype "passive")
		)
	)
	(footprint "antmicro-footprints:R_0402_1005Metric"
		(layer "B.Cu")
		(at 242.351 141.05 90)
		(descr "Resistor SMD 0402")
		(tags "resistor SMD 0402")
		(property "Reference" "R166"
			(at 1.425 1.324 270)
			(layer "B.SilkS")
			(effects
				(font
					(size 0.7 0.7)
					(thickness 0.15)
				)
				(justify left bottom mirror)
			)
		)
		(property "Value" "R_47k_0402"
			(at 0 -1.4 270)
			(layer "B.Fab")
			(effects
				(font
					(size 0.7 0.7)
					(thickness 0.15)
				)
				(justify left bottom mirror)
			)
		)
		(property "Description" "SMD Chip Resistor, 47 kohm, ± 1%, 62.5 mW, 0402 [1005 Metric], Thick Film, General Purpose"
			(at 0 0 90)
			(layer "F.Fab")
			(hide yes)
			(effects
				(font
					(size 1.27 1.27)
					(thickness 0.15)
				)
			)
		)
		(property "Author" "Antmicro"
			(at 383.401 -101.301 0)
			(layer "B.Fab")
			(hide yes)
			(effects
				(font
					(size 1 1)
					(thickness 0.15)
				)
				(justify mirror)
			)
		)
		(property "License" "Apache-2.0"
			(at 383.401 -101.301 0)
			(layer "B.Fab")
			(hide yes)
			(effects
				(font
					(size 1 1)
					(thickness 0.15)
				)
				(justify mirror)
			)
		)
		(property "MPN" "CR0402-FX-4702GLF"
			(at 383.401 -101.301 0)
			(layer "B.Fab")
			(hide yes)
			(effects
				(font
					(size 1 1)
					(thickness 0.15)
				)
				(justify mirror)
			)
		)
		(property "Manufacturer" "Bourns"
			(at 383.401 -101.301 0)
			(layer "B.Fab")
			(hide yes)
			(effects
				(font
					(size 1 1)
					(thickness 0.15)
				)
				(justify mirror)
			)
		)
		(property "Tolerance" "1%"
			(at 383.401 -101.301 0)
			(layer "B.Fab")
			(hide yes)
			(effects
				(font
					(size 1 1)
					(thickness 0.15)
				)
				(justify mirror)
			)
		)
		(property "Val" "47k"
			(at 383.401 -101.301 0)
			(layer "B.Fab")
			(hide yes)
			(effects
				(font
					(size 1 1)
					(thickness 0.15)
				)
				(justify mirror)
			)
		)
		(sheetname "USB PHY")
		(sheetfile "usb-phy.kicad_sch")
		(attr smd)
		(fp_rect
			(start -0.925 0.47)
			(end 0.925 -0.47)
			(stroke
				(width 0.05)
				(type default)
			)
			(fill no)
			(layer "B.CrtYd")
		)
		(fp_rect
			(start -0.5 0.25)
			(end 0.5 -0.25)
			(stroke
				(width 0.15)
				(type solid)
			)
			(fill no)
			(layer "B.Fab")
		)
		(pad "1" smd roundrect
			(at -0.48 0 90)
			(size 0.59 0.64)
			(layers "B.Cu" "B.Mask" "B.Paste")
			(roundrect_rratio 0.25)
			(net 878 "/USB PHY/~{BDBUS3}")
			(pintype "passive")
		)
		(pad "2" smd roundrect
			(at 0.48 0 90)
			(size 0.59 0.64)
			(layers "B.Cu" "B.Mask" "B.Paste")
			(roundrect_rratio 0.25)
			(net 707 "/USB PHY/FTDI_3V3")
			(pintype "passive")
		)
	)
	(footprint "antmicro-footprints:C_0402_1005Metric"
		(layer "B.Cu")
		(at 205.49 133 90)
		(descr "Capacitor SMD 0402")
		(tags "capacitor SMD 0402")
		(property "Reference" "C37"
			(at 29.525 28.7 270)
			(layer "B.SilkS")
			(effects
				(font
					(size 0.7 0.7)
					(thickness 0.15)
				)
				(justify left bottom mirror)
			)
		)
		(property "Value" "C_100n_0402"
			(at 0 -1.169 270)
			(layer "B.Fab")
			(effects
				(font
					(size 0.7 0.7)
					(thickness 0.15)
				)
				(justify left bottom mirror)
			)
		)
		(property "Description" "SMD Multilayer Ceramic Capacitor, 0.1 µF, 50 V, 0402 [1005 Metric], ± 10%, X5R, GRM Series"
			(at 0 0 90)
			(layer "F.Fab")
			(hide yes)
			(effects
				(font
					(size 1.27 1.27)
					(thickness 0.15)
				)
			)
		)
		(property "Author" "Antmicro"
			(at 338.49 -72.49 0)
			(layer "B.Fab")
			(hide yes)
			(effects
				(font
					(size 1 1)
					(thickness 0.15)
				)
				(justify mirror)
			)
		)
		(property "Dielectric" "X5R"
			(at 338.49 -72.49 0)
			(layer "B.Fab")
			(hide yes)
			(effects
				(font
					(size 1 1)
					(thickness 0.15)
				)
				(justify mirror)
			)
		)
		(property "License" "Apache-2.0"
			(at 338.49 -72.49 0)
			(layer "B.Fab")
			(hide yes)
			(effects
				(font
					(size 1 1)
					(thickness 0.15)
				)
				(justify mirror)
			)
		)
		(property "MPN" "GRM155R61H104KE14D"
			(at 338.49 -72.49 0)
			(layer "B.Fab")
			(hide yes)
			(effects
				(font
					(size 1 1)
					(thickness 0.15)
				)
				(justify mirror)
			)
		)
		(property "Manufacturer" "Murata"
			(at 338.49 -72.49 0)
			(layer "B.Fab")
			(hide yes)
			(effects
				(font
					(size 1 1)
					(thickness 0.15)
				)
				(justify mirror)
			)
		)
		(property "Val" "100n"
			(at 338.49 -72.49 0)
			(layer "B.Fab")
			(hide yes)
			(effects
				(font
					(size 1 1)
					(thickness 0.15)
				)
				(justify mirror)
			)
		)
		(property "Voltage" "50V"
			(at 338.49 -72.49 0)
			(layer "B.Fab")
			(hide yes)
			(effects
				(font
					(size 1 1)
					(thickness 0.15)
				)
				(justify mirror)
			)
		)
		(sheetname "FPGA Bank 14 & 15")
		(sheetfile "fpga-bank-14-15.kicad_sch")
		(attr smd)
		(fp_rect
			(start -0.925 0.47)
			(end 0.925 -0.47)
			(stroke
				(width 0.05)
				(type default)
			)
			(fill no)
			(layer "B.CrtYd")
		)
		(fp_line
			(start 0.504 -0.248)
			(end -0.494 -0.248)
			(stroke
				(width 0.15)
				(type solid)
			)
			(layer "B.Fab")
		)
		(fp_line
			(start -0.494 -0.248)
			(end -0.494 0.25)
			(stroke
				(width 0.15)
				(type solid)
			)
			(layer "B.Fab")
		)
		(fp_line
			(start 0.504 0.25)
			(end 0.504 -0.248)
			(stroke
				(width 0.15)
				(type solid)
			)
			(layer "B.Fab")
		)
		(fp_line
			(start -0.494 0.25)
			(end 0.504 0.25)
			(stroke
				(width 0.15)
				(type solid)
			)
			(layer "B.Fab")
		)
		(pad "1" smd roundrect
			(at -0.48 0 90)
			(size 0.59 0.64)
			(layers "B.Cu" "B.Mask" "B.Paste")
			(roundrect_rratio 0.25)
			(net 1 "GND")
			(pintype "passive")
		)
		(pad "2" smd roundrect
			(at 0.48 0 90)
			(size 0.59 0.64)
			(layers "B.Cu" "B.Mask" "B.Paste")
			(roundrect_rratio 0.25)
			(net 24 "+3V3")
			(pintype "passive")
		)
	)
	(footprint "antmicro-footprints:NetTie-2_SMD_Pad0.127mm"
		(layer "B.Cu")
		(at 254.101 127.2 -90)
		(descr "Net tie, 2 pin, 0.127mm  SMD pads")
		(tags "net tie")
		(property "Reference" "NT22"
			(at -0.128 1.345 90)
			(layer "B.SilkS")
			(hide yes)
			(effects
				(font
					(size 0.7 0.7)
					(thickness 0.15)
				)
				(justify left bottom mirror)
			)
		)
		(property "Value" "Net-Tie_2"
			(at 0 -1.199 90)
			(layer "B.Fab")
			(effects
				(font
					(size 0.7 0.7)
					(thickness 0.15)
				)
				(justify left bottom mirror)
			)
		)
		(property "Description" "Net tie, 2 pins"
			(at 0 0 270)
			(layer "F.Fab")
			(hide yes)
			(effects
				(font
					(size 1.27 1.27)
					(thickness 0.15)
				)
			)
		)
		(property "Author" "Antmicro"
			(at 126.901 381.301 0)
			(layer "B.Fab")
			(hide yes)
			(effects
				(font
					(size 1 1)
					(thickness 0.15)
				)
				(justify mirror)
			)
		)
		(property "License" "Apache-2.0"
			(at 126.901 381.301 0)
			(layer "B.Fab")
			(hide yes)
			(effects
				(font
					(size 1 1)
					(thickness 0.15)
				)
				(justify mirror)
			)
		)
		(property "MPN" ""
			(at 126.901 381.301 0)
			(layer "B.Fab")
			(hide yes)
			(effects
				(font
					(size 1 1)
					(thickness 0.15)
				)
				(justify mirror)
			)
		)
		(property "Manufacturer" ""
			(at 126.901 381.301 0)
			(layer "B.Fab")
			(hide yes)
			(effects
				(font
					(size 1 1)
					(thickness 0.15)
				)
				(justify mirror)
			)
		)
		(sheetname "Supervisior MCU")
		(sheetfile "supervisor-mcu.kicad_sch")
		(attr exclude_from_pos_files)
		(net_tie_pad_groups "1, 2")
		(fp_poly
			(pts
				(xy -0.0635 0.0635) (xy 0.0625 0.0635) (xy 0.0625 -0.0635) (xy -0.0635 -0.0635)
			)
			(stroke
				(width 0)
				(type solid)
			)
			(fill yes)
			(layer "B.Cu")
		)
		(pad "1" smd roundrect
			(at -0.127 0 90)
			(size 0.127 0.127)
			(layers "B.Cu")
			(roundrect_rratio 0.5)
			(chamfer_ratio 0)
			(chamfer top_left bottom_left)
			(net 1336 "/I2C.SDA")
			(pinfunction "1")
			(pintype "passive")
		)
		(pad "2" smd roundrect
			(at 0.126 0 270)
			(size 0.127 0.127)
			(layers "B.Cu")
			(roundrect_rratio 0.5)
			(chamfer_ratio 0)
			(chamfer top_left bottom_left)
			(net 1337 "/SUP_MCU.SDA")
			(pinfunction "2")
			(pintype "passive")
		)
	)
	(footprint "antmicro-footprints:C_0201"
		(layer "B.Cu")
		(at 201.5 126.45)
		(descr "Capacitor SMD 0201")
		(tags "capacitor SMD 0201")
		(property "Reference" "C122"
			(at 24.475 -29.525 0)
			(layer "B.SilkS")
			(effects
				(font
					(size 0.7 0.7)
					(thickness 0.15)
				)
				(justify right bottom mirror)
			)
		)
		(property "Value" "C_100n_0201"
			(at 0 -1.4 0)
			(layer "B.Fab")
			(effects
				(font
					(size 0.7 0.7)
					(thickness 0.15)
				)
				(justify right bottom mirror)
			)
		)
		(property "Description" "SMD Multilayer Ceramic Capacitor, 0.1 µF, 6.3 V, 0201 [0603 Metric], ± 10%, X6S, CC Series"
			(at 0 0 0)
			(layer "F.Fab")
			(hide yes)
			(effects
				(font
					(size 1.27 1.27)
					(thickness 0.15)
				)
			)
		)
		(property "Author" "Antmicro"
			(at 0 0 0)
			(layer "B.Fab")
			(hide yes)
			(effects
				(font
					(size 1 1)
					(thickness 0.15)
				)
				(justify mirror)
			)
		)
		(property "Dielectric" ""
			(at 0 0 0)
			(layer "B.Fab")
			(hide yes)
			(effects
				(font
					(size 1 1)
					(thickness 0.15)
				)
				(justify mirror)
			)
		)
		(property "License" "Apache-2.0"
			(at 0 0 0)
			(layer "B.Fab")
			(hide yes)
			(effects
				(font
					(size 1 1)
					(thickness 0.15)
				)
				(justify mirror)
			)
		)
		(property "MPN" "CC0201KRX6S5BB104"
			(at 0 0 0)
			(layer "B.Fab")
			(hide yes)
			(effects
				(font
					(size 1 1)
					(thickness 0.15)
				)
				(justify mirror)
			)
		)
		(property "Manufacturer" "YAGEO"
			(at 0 0 0)
			(layer "B.Fab")
			(hide yes)
			(effects
				(font
					(size 1 1)
					(thickness 0.15)
				)
				(justify mirror)
			)
		)
		(property "Val" "100n"
			(at 0 0 0)
			(layer "B.Fab")
			(hide yes)
			(effects
				(font
					(size 1 1)
					(thickness 0.15)
				)
				(justify mirror)
			)
		)
		(property "Voltage" ""
			(at 0 0 0)
			(layer "B.Fab")
			(hide yes)
			(effects
				(font
					(size 1 1)
					(thickness 0.15)
				)
				(justify mirror)
			)
		)
		(sheetname "FPGA supply")
		(sheetfile "fpga-supply.kicad_sch")
		(attr smd)
		(fp_rect
			(start -0.7 0.35)
			(end 0.7 -0.35)
			(stroke
				(width 0.05)
				(type default)
			)
			(fill no)
			(layer "B.CrtYd")
		)
		(fp_rect
			(start 0.3 -0.15)
			(end -0.301 0.149)
			(stroke
				(width 0.15)
				(type solid)
			)
			(fill no)
			(layer "B.Fab")
		)
		(pad "" smd roundrect
			(at -0.349 0.002)
			(size 0.318 0.36)
			(layers "B.Paste")
			(roundrect_rratio 0.25)
		)
		(pad "" smd roundrect
			(at 0.341 0.002)
			(size 0.318 0.36)
			(layers "B.Paste")
			(roundrect_rratio 0.25)
		)
		(pad "1" smd roundrect
			(at -0.321 0.002)
			(size 0.46 0.4)
			(layers "B.Cu" "B.Mask")
			(roundrect_rratio 0.25)
			(net 1 "GND")
			(pintype "passive")
		)
		(pad "2" smd roundrect
			(at 0.32 0.002)
			(size 0.46 0.4)
			(layers "B.Cu" "B.Mask")
			(roundrect_rratio 0.25)
			(net 650 "+1V0")
			(pintype "passive")
		)
	)
)
